(kicad_pcb
	(version 20260206)
	(generator "pcbnew")
	(generator_version "10.0")
	(general
		(thickness 1.6)
		(legacy_teardrops no)
	)
	(paper "A4")
	(title_block
		(title "9054_F0T_PDB_BD_GPU_F_V04_1213_1550_OCP.brd")
		(comment 1 "Grand Teton / footprints 434-439 of 608")
	)
	(layers
		(0 "F.Cu" signal "TOP")
		(4 "In1.Cu" signal "GND")
		(6 "In2.Cu" signal "IN1")
		(8 "In3.Cu" signal "GND1")
		(10 "In4.Cu" signal "VCC")
		(12 "In5.Cu" signal "VCC1")
		(14 "In6.Cu" signal "GND2")
		(16 "In7.Cu" signal "IN2")
		(18 "In8.Cu" signal "GND3")
		(2 "B.Cu" signal "BOTTOM")
		(9 "F.Adhes" user "F.Adhesive")
		(11 "B.Adhes" user "B.Adhesive")
		(13 "F.Paste" user "Package Geometry/Pastemask Top")
		(15 "B.Paste" user "Package Geometry/Pastemask Bottom")
		(5 "F.SilkS" user "Ref Des/Silkscreen Top")
		(7 "B.SilkS" user "Ref Des/Silkscreen Bottom")
		(1 "F.Mask" user "Board Geometry/Soldermask Top")
		(3 "B.Mask" user "Board Geometry/Soldermask Bottom")
		(17 "Dwgs.User" user "User.Drawings")
		(19 "Cmts.User" user "User.Comments")
		(21 "Eco1.User" user "User.Eco1")
		(23 "Eco2.User" user "User.Eco2")
		(25 "Edge.Cuts" user "Board Geometry/Outline")
		(27 "Margin" user)
		(31 "F.CrtYd" user "Package Geometry/Place Bound Top")
		(29 "B.CrtYd" user "Package Geometry/Place Bound Bottom")
		(35 "F.Fab" user "Ref Des/Assembly Top")
		(33 "B.Fab" user "Ref Des/Assembly Bottom")
	)
	(footprint ""
		(layer "B.Cu")
		(at 161.717736 -67.183)
		(property "Reference" "R5871"
			(at 0 0 0)
			(layer "B.SilkS")
			(hide yes)
			(effects
				(font
					(size 1.27 1.27)
				)
				(justify mirror)
			)
		)
		(property "Value" ""
			(at 0 0 0)
			(layer "B.Fab")
			(effects
				(font
					(size 1.27 1.27)
				)
				(justify mirror)
			)
		)
		(duplicate_pad_numbers_are_jumpers no)
		(fp_line
			(start -0.7874 -0.4064)
			(end -0.7874 0.4064)
			(stroke
				(width 0.1524)
				(type default)
			)
			(layer "B.SilkS")
		)
		(fp_line
			(start -0.7874 0.4064)
			(end 0.7874 0.4064)
			(stroke
				(width 0.1524)
				(type default)
			)
			(layer "B.SilkS")
		)
		(fp_line
			(start 0.7874 -0.4064)
			(end -0.7874 -0.4064)
			(stroke
				(width 0.1524)
				(type default)
			)
			(layer "B.SilkS")
		)
		(fp_line
			(start 0.7874 0.4064)
			(end 0.7874 -0.4064)
			(stroke
				(width 0.1524)
				(type default)
			)
			(layer "B.SilkS")
		)
		(fp_line
			(start -0.67945 -0.3048)
			(end -0.67945 0.3048)
			(stroke
				(width 0.1)
				(type default)
			)
			(layer "B.Fab")
		)
		(fp_line
			(start -0.67945 0.3048)
			(end -0.120396 0.3048)
			(stroke
				(width 0.1)
				(type default)
			)
			(layer "B.Fab")
		)
		(fp_line
			(start -0.12065 -0.3048)
			(end -0.67945 -0.3048)
			(stroke
				(width 0.1)
				(type default)
			)
			(layer "B.Fab")
		)
		(fp_line
			(start -0.12065 -0.2794)
			(end -0.12065 -0.3048)
			(stroke
				(width 0.1)
				(type default)
			)
			(layer "B.Fab")
		)
		(fp_line
			(start -0.120396 0.2794)
			(end 0.12065 0.2794)
			(stroke
				(width 0.1)
				(type default)
			)
			(layer "B.Fab")
		)
		(fp_line
			(start -0.120396 0.3048)
			(end -0.120396 0.2794)
			(stroke
				(width 0.1)
				(type default)
			)
			(layer "B.Fab")
		)
		(fp_line
			(start 0.12065 -0.305054)
			(end 0.12065 -0.2794)
			(stroke
				(width 0.1)
				(type default)
			)
			(layer "B.Fab")
		)
		(fp_line
			(start 0.12065 -0.2794)
			(end -0.12065 -0.2794)
			(stroke
				(width 0.1)
				(type default)
			)
			(layer "B.Fab")
		)
		(fp_line
			(start 0.12065 0.2794)
			(end 0.12065 0.3048)
			(stroke
				(width 0.1)
				(type default)
			)
			(layer "B.Fab")
		)
		(fp_line
			(start 0.12065 0.3048)
			(end 0.67945 0.3048)
			(stroke
				(width 0.1)
				(type default)
			)
			(layer "B.Fab")
		)
		(fp_line
			(start 0.67945 -0.305054)
			(end 0.12065 -0.305054)
			(stroke
				(width 0.1)
				(type default)
			)
			(layer "B.Fab")
		)
		(fp_line
			(start 0.67945 0.3048)
			(end 0.67945 -0.305054)
			(stroke
				(width 0.1)
				(type default)
			)
			(layer "B.Fab")
		)
		(pad "1" smd circle
			(at 0.40005 0 180)
			(size 0 0)
			(layers "B.Cu" "B.Mask" "B.Paste")
			(net "SMB_P52V_PDB_SDA")
		)
		(pad "2" smd circle
			(at -0.40005 0 180)
			(size 0 0)
			(layers "B.Cu" "B.Mask" "B.Paste")
			(net "SMB_P52V_HS2_SDAI")
		)
	)
	(footprint ""
		(layer "B.Cu")
		(at 413.639 -37.973)
		(property "Reference" "R5937"
			(at 0 0 0)
			(layer "B.SilkS")
			(hide yes)
			(effects
				(font
					(size 1.27 1.27)
				)
				(justify mirror)
			)
		)
		(property "Value" ""
			(at 0 0 0)
			(layer "B.Fab")
			(effects
				(font
					(size 1.27 1.27)
				)
				(justify mirror)
			)
		)
		(duplicate_pad_numbers_are_jumpers no)
		(fp_line
			(start -0.7874 -0.4064)
			(end -0.7874 0.4064)
			(stroke
				(width 0.1524)
				(type default)
			)
			(layer "B.SilkS")
		)
		(fp_line
			(start -0.7874 0.4064)
			(end 0.7874 0.4064)
			(stroke
				(width 0.1524)
				(type default)
			)
			(layer "B.SilkS")
		)
		(fp_line
			(start 0.7874 -0.4064)
			(end -0.7874 -0.4064)
			(stroke
				(width 0.1524)
				(type default)
			)
			(layer "B.SilkS")
		)
		(fp_line
			(start 0.7874 0.4064)
			(end 0.7874 -0.4064)
			(stroke
				(width 0.1524)
				(type default)
			)
			(layer "B.SilkS")
		)
		(fp_line
			(start -0.67945 -0.3048)
			(end -0.67945 0.3048)
			(stroke
				(width 0.1)
				(type default)
			)
			(layer "B.Fab")
		)
		(fp_line
			(start -0.67945 0.3048)
			(end -0.120396 0.3048)
			(stroke
				(width 0.1)
				(type default)
			)
			(layer "B.Fab")
		)
		(fp_line
			(start -0.12065 -0.3048)
			(end -0.67945 -0.3048)
			(stroke
				(width 0.1)
				(type default)
			)
			(layer "B.Fab")
		)
		(fp_line
			(start -0.12065 -0.2794)
			(end -0.12065 -0.3048)
			(stroke
				(width 0.1)
				(type default)
			)
			(layer "B.Fab")
		)
		(fp_line
			(start -0.120396 0.2794)
			(end 0.12065 0.2794)
			(stroke
				(width 0.1)
				(type default)
			)
			(layer "B.Fab")
		)
		(fp_line
			(start -0.120396 0.3048)
			(end -0.120396 0.2794)
			(stroke
				(width 0.1)
				(type default)
			)
			(layer "B.Fab")
		)
		(fp_line
			(start 0.12065 -0.305054)
			(end 0.12065 -0.2794)
			(stroke
				(width 0.1)
				(type default)
			)
			(layer "B.Fab")
		)
		(fp_line
			(start 0.12065 -0.2794)
			(end -0.12065 -0.2794)
			(stroke
				(width 0.1)
				(type default)
			)
			(layer "B.Fab")
		)
		(fp_line
			(start 0.12065 0.2794)
			(end 0.12065 0.3048)
			(stroke
				(width 0.1)
				(type default)
			)
			(layer "B.Fab")
		)
		(fp_line
			(start 0.12065 0.3048)
			(end 0.67945 0.3048)
			(stroke
				(width 0.1)
				(type default)
			)
			(layer "B.Fab")
		)
		(fp_line
			(start 0.67945 -0.305054)
			(end 0.12065 -0.305054)
			(stroke
				(width 0.1)
				(type default)
			)
			(layer "B.Fab")
		)
		(fp_line
			(start 0.67945 0.3048)
			(end 0.67945 -0.305054)
			(stroke
				(width 0.1)
				(type default)
			)
			(layer "B.Fab")
		)
		(pad "1" smd circle
			(at 0.40005 0 180)
			(size 0 0)
			(layers "B.Cu" "B.Mask" "B.Paste")
			(net "PCA9555_2_A2")
		)
		(pad "2" smd circle
			(at -0.40005 0 180)
			(size 0 0)
			(layers "B.Cu" "B.Mask" "B.Paste")
			(net "GND")
		)
	)
	(footprint ""
		(layer "B.Cu")
		(at 269.9004 -76.454 -90)
		(property "Reference" "PC10"
			(at 0 0 90)
			(layer "B.SilkS")
			(hide yes)
			(effects
				(font
					(size 1.27 1.27)
				)
				(justify mirror)
			)
		)
		(property "Value" ""
			(at 0 0 90)
			(layer "B.Fab")
			(effects
				(font
					(size 1.27 1.27)
				)
				(justify mirror)
			)
		)
		(duplicate_pad_numbers_are_jumpers no)
		(fp_line
			(start -0.7874 0.4064)
			(end 0.7874 0.4064)
			(stroke
				(width 0.1524)
				(type default)
			)
			(layer "B.SilkS")
		)
		(fp_line
			(start 0.7874 0.4064)
			(end 0.7874 -0.4064)
			(stroke
				(width 0.1524)
				(type default)
			)
			(layer "B.SilkS")
		)
		(fp_line
			(start -0.7874 -0.4064)
			(end -0.7874 0.4064)
			(stroke
				(width 0.1524)
				(type default)
			)
			(layer "B.SilkS")
		)
		(fp_line
			(start 0.7874 -0.4064)
			(end -0.7874 -0.4064)
			(stroke
				(width 0.1524)
				(type default)
			)
			(layer "B.SilkS")
		)
		(fp_line
			(start -0.67945 0.3048)
			(end -0.120396 0.3048)
			(stroke
				(width 0.1)
				(type default)
			)
			(layer "B.Fab")
		)
		(fp_line
			(start -0.120396 0.3048)
			(end -0.120396 0.2794)
			(stroke
				(width 0.1)
				(type default)
			)
			(layer "B.Fab")
		)
		(fp_line
			(start 0.12065 0.3048)
			(end 0.67945 0.3048)
			(stroke
				(width 0.1)
				(type default)
			)
			(layer "B.Fab")
		)
		(fp_line
			(start 0.67945 0.3048)
			(end 0.67945 -0.305054)
			(stroke
				(width 0.1)
				(type default)
			)
			(layer "B.Fab")
		)
		(fp_line
			(start -0.120396 0.2794)
			(end 0.12065 0.2794)
			(stroke
				(width 0.1)
				(type default)
			)
			(layer "B.Fab")
		)
		(fp_line
			(start 0.12065 0.2794)
			(end 0.12065 0.3048)
			(stroke
				(width 0.1)
				(type default)
			)
			(layer "B.Fab")
		)
		(fp_line
			(start -0.12065 -0.2794)
			(end -0.12065 -0.3048)
			(stroke
				(width 0.1)
				(type default)
			)
			(layer "B.Fab")
		)
		(fp_line
			(start 0.12065 -0.2794)
			(end -0.12065 -0.2794)
			(stroke
				(width 0.1)
				(type default)
			)
			(layer "B.Fab")
		)
		(fp_line
			(start -0.67945 -0.3048)
			(end -0.67945 0.3048)
			(stroke
				(width 0.1)
				(type default)
			)
			(layer "B.Fab")
		)
		(fp_line
			(start -0.12065 -0.3048)
			(end -0.67945 -0.3048)
			(stroke
				(width 0.1)
				(type default)
			)
			(layer "B.Fab")
		)
		(fp_line
			(start 0.12065 -0.305054)
			(end 0.12065 -0.2794)
			(stroke
				(width 0.1)
				(type default)
			)
			(layer "B.Fab")
		)
		(fp_line
			(start 0.67945 -0.305054)
			(end 0.12065 -0.305054)
			(stroke
				(width 0.1)
				(type default)
			)
			(layer "B.Fab")
		)
		(pad "1" smd circle
			(at 0.40005 0 90)
			(size 0 0)
			(layers "B.Cu" "B.Mask" "B.Paste")
			(net "P52V_HS1_VREG")
		)
		(pad "2" smd circle
			(at -0.40005 0 90)
			(size 0 0)
			(layers "B.Cu" "B.Mask" "B.Paste")
			(net "GND_FIELD_SIGNAL")
		)
	)
	(footprint ""
		(layer "B.Cu")
		(at 163.368736 -77.089 180)
		(property "Reference" "PC602"
			(at 0 0 0)
			(layer "B.SilkS")
			(hide yes)
			(effects
				(font
					(size 1.27 1.27)
				)
				(justify mirror)
			)
		)
		(property "Value" ""
			(at 0 0 0)
			(layer "B.Fab")
			(effects
				(font
					(size 1.27 1.27)
				)
				(justify mirror)
			)
		)
		(duplicate_pad_numbers_are_jumpers no)
		(fp_line
			(start 1.2954 0.5842)
			(end 1.2954 -0.5842)
			(stroke
				(width 0.1524)
				(type default)
			)
			(layer "B.SilkS")
		)
		(fp_line
			(start 1.2954 -0.5842)
			(end -1.2954 -0.5842)
			(stroke
				(width 0.1524)
				(type default)
			)
			(layer "B.SilkS")
		)
		(fp_line
			(start -1.2954 0.5842)
			(end 1.2954 0.5842)
			(stroke
				(width 0.1524)
				(type default)
			)
			(layer "B.SilkS")
		)
		(fp_line
			(start -1.2954 -0.5842)
			(end -1.2954 0.5842)
			(stroke
				(width 0.1524)
				(type default)
			)
			(layer "B.SilkS")
		)
		(fp_line
			(start 1.1938 0.4064)
			(end 1.1938 -0.4064)
			(stroke
				(width 0.1)
				(type default)
			)
			(layer "B.Fab")
		)
		(fp_line
			(start 1.1938 -0.4064)
			(end 0.8636 -0.4064)
			(stroke
				(width 0.1)
				(type default)
			)
			(layer "B.Fab")
		)
		(fp_line
			(start 0.8636 0.4572)
			(end 0.8636 0.4064)
			(stroke
				(width 0.1)
				(type default)
			)
			(layer "B.Fab")
		)
		(fp_line
			(start 0.8636 0.4064)
			(end 1.1938 0.4064)
			(stroke
				(width 0.1)
				(type default)
			)
			(layer "B.Fab")
		)
		(fp_line
			(start 0.8636 -0.4064)
			(end 0.8636 -0.4572)
			(stroke
				(width 0.1)
				(type default)
			)
			(layer "B.Fab")
		)
		(fp_line
			(start 0.8636 -0.4572)
			(end -0.8636 -0.4572)
			(stroke
				(width 0.1)
				(type default)
			)
			(layer "B.Fab")
		)
		(fp_line
			(start -0.8636 0.4572)
			(end 0.8636 0.4572)
			(stroke
				(width 0.1)
				(type default)
			)
			(layer "B.Fab")
		)
		(fp_line
			(start -0.8636 0.4064)
			(end -0.8636 0.4572)
			(stroke
				(width 0.1)
				(type default)
			)
			(layer "B.Fab")
		)
		(fp_line
			(start -0.8636 -0.4064)
			(end -1.1938 -0.4064)
			(stroke
				(width 0.1)
				(type default)
			)
			(layer "B.Fab")
		)
		(fp_line
			(start -0.8636 -0.4572)
			(end -0.8636 -0.4064)
			(stroke
				(width 0.1)
				(type default)
			)
			(layer "B.Fab")
		)
		(fp_line
			(start -1.1938 0.4064)
			(end -0.8636 0.4064)
			(stroke
				(width 0.1)
				(type default)
			)
			(layer "B.Fab")
		)
		(fp_line
			(start -1.1938 -0.4064)
			(end -1.1938 0.4064)
			(stroke
				(width 0.1)
				(type default)
			)
			(layer "B.Fab")
		)
		(pad "1" smd rect
			(at 0.7366 0 90)
			(size 0.7112 0.8128)
			(layers "B.Cu" "B.Mask" "B.Paste")
			(net "HS2_TMR2")
		)
		(pad "2" smd rect
			(at -0.7366 0 90)
			(size 0.7112 0.8128)
			(layers "B.Cu" "B.Mask" "B.Paste")
			(net "GND1_FIELD_SIGNAL")
		)
	)
	(footprint ""
		(layer "B.Cu")
		(at 286.2834 -65.278 90)
		(property "Reference" "PR210"
			(at 0 0 90)
			(layer "B.SilkS")
			(hide yes)
			(effects
				(font
					(size 1.27 1.27)
				)
				(justify mirror)
			)
		)
		(property "Value" ""
			(at 0 0 90)
			(layer "B.Fab")
			(effects
				(font
					(size 1.27 1.27)
				)
				(justify mirror)
			)
		)
		(duplicate_pad_numbers_are_jumpers no)
		(fp_line
			(start 0.7874 -0.4064)
			(end -0.7874 -0.4064)
			(stroke
				(width 0.1524)
				(type default)
			)
			(layer "B.SilkS")
		)
		(fp_line
			(start -0.7874 -0.4064)
			(end -0.7874 0.4064)
			(stroke
				(width 0.1524)
				(type default)
			)
			(layer "B.SilkS")
		)
		(fp_line
			(start 0.7874 0.4064)
			(end 0.7874 -0.4064)
			(stroke
				(width 0.1524)
				(type default)
			)
			(layer "B.SilkS")
		)
		(fp_line
			(start -0.7874 0.4064)
			(end 0.7874 0.4064)
			(stroke
				(width 0.1524)
				(type default)
			)
			(layer "B.SilkS")
		)
		(fp_line
			(start 0.67945 -0.305054)
			(end 0.12065 -0.305054)
			(stroke
				(width 0.1)
				(type default)
			)
			(layer "B.Fab")
		)
		(fp_line
			(start 0.12065 -0.305054)
			(end 0.12065 -0.2794)
			(stroke
				(width 0.1)
				(type default)
			)
			(layer "B.Fab")
		)
		(fp_line
			(start -0.12065 -0.3048)
			(end -0.67945 -0.3048)
			(stroke
				(width 0.1)
				(type default)
			)
			(layer "B.Fab")
		)
		(fp_line
			(start -0.67945 -0.3048)
			(end -0.67945 0.3048)
			(stroke
				(width 0.1)
				(type default)
			)
			(layer "B.Fab")
		)
		(fp_line
			(start 0.12065 -0.2794)
			(end -0.12065 -0.2794)
			(stroke
				(width 0.1)
				(type default)
			)
			(layer "B.Fab")
		)
		(fp_line
			(start -0.12065 -0.2794)
			(end -0.12065 -0.3048)
			(stroke
				(width 0.1)
				(type default)
			)
			(layer "B.Fab")
		)
		(fp_line
			(start 0.12065 0.2794)
			(end 0.12065 0.3048)
			(stroke
				(width 0.1)
				(type default)
			)
			(layer "B.Fab")
		)
		(fp_line
			(start -0.120396 0.2794)
			(end 0.12065 0.2794)
			(stroke
				(width 0.1)
				(type default)
			)
			(layer "B.Fab")
		)
		(fp_line
			(start 0.67945 0.3048)
			(end 0.67945 -0.305054)
			(stroke
				(width 0.1)
				(type default)
			)
			(layer "B.Fab")
		)
		(fp_line
			(start 0.12065 0.3048)
			(end 0.67945 0.3048)
			(stroke
				(width 0.1)
				(type default)
			)
			(layer "B.Fab")
		)
		(fp_line
			(start -0.120396 0.3048)
			(end -0.120396 0.2794)
			(stroke
				(width 0.1)
				(type default)
			)
			(layer "B.Fab")
		)
		(fp_line
			(start -0.67945 0.3048)
			(end -0.120396 0.3048)
			(stroke
				(width 0.1)
				(type default)
			)
			(layer "B.Fab")
		)
		(pad "1" smd circle
			(at 0.40005 0 270)
			(size 0 0)
			(layers "B.Cu" "B.Mask" "B.Paste")
			(net "P52V_HS1_TMR")
		)
		(pad "2" smd circle
			(at -0.40005 0 270)
			(size 0 0)
			(layers "B.Cu" "B.Mask" "B.Paste")
			(net "HS1_TMR1")
		)
	)
	(footprint ""
		(layer "B.Cu")
		(at 337.3374 -50.6476 90)
		(property "Reference" "R5862"
			(at 0 0 90)
			(layer "B.SilkS")
			(hide yes)
			(effects
				(font
					(size 1.27 1.27)
				)
				(justify mirror)
			)
		)
		(property "Value" ""
			(at 0 0 90)
			(layer "B.Fab")
			(effects
				(font
					(size 1.27 1.27)
				)
				(justify mirror)
			)
		)
		(duplicate_pad_numbers_are_jumpers no)
		(fp_line
			(start 0.7874 -0.4064)
			(end -0.7874 -0.4064)
			(stroke
				(width 0.1524)
				(type default)
			)
			(layer "B.SilkS")
		)
		(fp_line
			(start -0.7874 -0.4064)
			(end -0.7874 0.4064)
			(stroke
				(width 0.1524)
				(type default)
			)
			(layer "B.SilkS")
		)
		(fp_line
			(start 0.7874 0.4064)
			(end 0.7874 -0.4064)
			(stroke
				(width 0.1524)
				(type default)
			)
			(layer "B.SilkS")
		)
		(fp_line
			(start -0.7874 0.4064)
			(end 0.7874 0.4064)
			(stroke
				(width 0.1524)
				(type default)
			)
			(layer "B.SilkS")
		)
		(fp_line
			(start 0.67945 -0.305054)
			(end 0.12065 -0.305054)
			(stroke
				(width 0.1)
				(type default)
			)
			(layer "B.Fab")
		)
		(fp_line
			(start 0.12065 -0.305054)
			(end 0.12065 -0.2794)
			(stroke
				(width 0.1)
				(type default)
			)
			(layer "B.Fab")
		)
		(fp_line
			(start -0.12065 -0.3048)
			(end -0.67945 -0.3048)
			(stroke
				(width 0.1)
				(type default)
			)
			(layer "B.Fab")
		)
		(fp_line
			(start -0.67945 -0.3048)
			(end -0.67945 0.3048)
			(stroke
				(width 0.1)
				(type default)
			)
			(layer "B.Fab")
		)
		(fp_line
			(start 0.12065 -0.2794)
			(end -0.12065 -0.2794)
			(stroke
				(width 0.1)
				(type default)
			)
			(layer "B.Fab")
		)
		(fp_line
			(start -0.12065 -0.2794)
			(end -0.12065 -0.3048)
			(stroke
				(width 0.1)
				(type default)
			)
			(layer "B.Fab")
		)
		(fp_line
			(start 0.12065 0.2794)
			(end 0.12065 0.3048)
			(stroke
				(width 0.1)
				(type default)
			)
			(layer "B.Fab")
		)
		(fp_line
			(start -0.120396 0.2794)
			(end 0.12065 0.2794)
			(stroke
				(width 0.1)
				(type default)
			)
			(layer "B.Fab")
		)
		(fp_line
			(start 0.67945 0.3048)
			(end 0.67945 -0.305054)
			(stroke
				(width 0.1)
				(type default)
			)
			(layer "B.Fab")
		)
		(fp_line
			(start 0.12065 0.3048)
			(end 0.67945 0.3048)
			(stroke
				(width 0.1)
				(type default)
			)
			(layer "B.Fab")
		)
		(fp_line
			(start -0.120396 0.3048)
			(end -0.120396 0.2794)
			(stroke
				(width 0.1)
				(type default)
			)
			(layer "B.Fab")
		)
		(fp_line
			(start -0.67945 0.3048)
			(end -0.120396 0.3048)
			(stroke
				(width 0.1)
				(type default)
			)
			(layer "B.Fab")
		)
		(pad "1" smd circle
			(at 0.40005 0 270)
			(size 0 0)
			(layers "B.Cu" "B.Mask" "B.Paste")
			(net "P52V_HS1_GATE1_R")
		)
		(pad "2" smd circle
			(at -0.40005 0 270)
			(size 0 0)
			(layers "B.Cu" "B.Mask" "B.Paste")
			(net "P52V_HS1_4287_GATE_R")
		)
	)
)
